(kicad_pcb
	(version 20241229)
	(generator "pcbnew")
	(generator_version "9.0")
	(general
		(thickness 1.61)
		(legacy_teardrops no)
	)
	(paper "A3")
	(title_block
		(title "RDIMM DDR5 Tester")
		(date "2026-05-21")
		(rev "2.2.0")
		(company "Antmicro")
		(comment 9 "footprints 794-796 of 796")
	)
	(layers
		(0 "F.Cu" signal)
		(4 "In1.Cu" power)
		(6 "In2.Cu" mixed)
		(8 "In3.Cu" power)
		(10 "In4.Cu" mixed)
		(12 "In5.Cu" power)
		(14 "In6.Cu" mixed)
		(16 "In7.Cu" power)
		(18 "In8.Cu" power)
		(20 "In9.Cu" mixed)
		(22 "In10.Cu" power)
		(2 "B.Cu" signal)
		(9 "F.Adhes" user "F.Adhesive")
		(11 "B.Adhes" user "B.Adhesive")
		(13 "F.Paste" user)
		(15 "B.Paste" user)
		(5 "F.SilkS" user "F.Silkscreen")
		(7 "B.SilkS" user "B.Silkscreen")
		(1 "F.Mask" user)
		(3 "B.Mask" user)
		(17 "Dwgs.User" user "User.Drawings")
		(19 "Cmts.User" user "User.Comments")
		(21 "Eco1.User" user "User.Eco1")
		(23 "Eco2.User" user "User.Eco2")
		(25 "Edge.Cuts" user)
		(27 "Margin" user)
		(31 "F.CrtYd" user "F.Courtyard")
		(29 "B.CrtYd" user "B.Courtyard")
		(35 "F.Fab" user)
		(33 "B.Fab" user)
	)
	(footprint "antmicro-footprints:Coax_Conn_U.FL"
		(layer "B.Cu")
		(at 136.9 102.67 -90)
		(descr "https://media.digikey.com/pdf/Data%20Sheets/Hirose%20PDFs/UFL%20Series.pdf")
		(property "Reference" "J16"
			(at 3.38 -0.15 180)
			(layer "B.SilkS")
			(hide yes)
			(effects
				(font
					(size 0.7 0.7)
					(thickness 0.15)
				)
				(justify left bottom mirror)
			)
		)
		(property "Value" "U_FL-R-SMT-1"
			(at -4.13 -2.52 90)
			(layer "B.Fab")
			(effects
				(font
					(size 0.7 0.7)
					(thickness 0.15)
				)
				(justify left bottom mirror)
			)
		)
		(property "Datasheet" "https://media.digikey.com/pdf/Data%20Sheets/Hirose%20PDFs/UFL%20Series.pdf"
			(at 0 0 270)
			(layer "F.Fab")
			(hide yes)
			(effects
				(font
					(size 1.27 1.27)
					(thickness 0.15)
				)
			)
		)
		(property "MPN" "U.FL-R-SMT-1(10)"
			(at 0 0 270)
			(unlocked yes)
			(layer "B.Fab")
			(hide yes)
			(effects
				(font
					(size 1 1)
					(thickness 0.15)
				)
				(justify mirror)
			)
		)
		(property "Manufacturer" "Hirose Electric"
			(at 0 0 270)
			(unlocked yes)
			(layer "B.Fab")
			(hide yes)
			(effects
				(font
					(size 1 1)
					(thickness 0.15)
				)
				(justify mirror)
			)
		)
		(property "Author" "Antmicro"
			(at 0 0 270)
			(unlocked yes)
			(layer "B.Fab")
			(hide yes)
			(effects
				(font
					(size 1 1)
					(thickness 0.15)
				)
				(justify mirror)
			)
		)
		(property "License" "Apache-2.0"
			(at 0 0 270)
			(unlocked yes)
			(layer "B.Fab")
			(hide yes)
			(effects
				(font
					(size 1 1)
					(thickness 0.15)
				)
				(justify mirror)
			)
		)
		(sheetname "/Debug FTDI + VNA/")
		(sheetfile "debug-ftdi.kicad_sch")
		(attr smd)
		(fp_line
			(start -1.613 1.651)
			(end -1.113 1.651)
			(stroke
				(width 0.15)
				(type solid)
			)
			(layer "B.SilkS")
		)
		(fp_line
			(start -1.613 1.651)
			(end -1.613 1.325)
			(stroke
				(width 0.15)
				(type solid)
			)
			(layer "B.SilkS")
		)
		(fp_line
			(start 1.588 1.651)
			(end 1.088 1.651)
			(stroke
				(width 0.15)
				(type solid)
			)
			(layer "B.SilkS")
		)
		(fp_line
			(start 1.588 1.651)
			(end 1.588 1.325)
			(stroke
				(width 0.15)
				(type solid)
			)
			(layer "B.SilkS")
		)
		(fp_line
			(start -1.613 -1.648)
			(end -1.613 -1.325)
			(stroke
				(width 0.15)
				(type solid)
			)
			(layer "B.SilkS")
		)
		(fp_line
			(start -1.613 -1.648)
			(end -1.113 -1.648)
			(stroke
				(width 0.15)
				(type solid)
			)
			(layer "B.SilkS")
		)
		(fp_line
			(start 1.588 -1.648)
			(end 1.588 -1.325)
			(stroke
				(width 0.15)
				(type solid)
			)
			(layer "B.SilkS")
		)
		(fp_line
			(start 1.588 -1.648)
			(end 1.088 -1.648)
			(stroke
				(width 0.15)
				(type solid)
			)
			(layer "B.SilkS")
		)
		(fp_rect
			(start -2 2.051)
			(end 1.999 -2.05)
			(stroke
				(width 0.05)
				(type solid)
			)
			(fill no)
			(layer "B.CrtYd")
		)
		(fp_line
			(start -1.512 1.551)
			(end 1.487 1.551)
			(stroke
				(width 0.15)
				(type solid)
			)
			(layer "B.Fab")
		)
		(fp_line
			(start -1.512 -1.55)
			(end -1.512 1.551)
			(stroke
				(width 0.15)
				(type solid)
			)
			(layer "B.Fab")
		)
		(fp_line
			(start -1.512 -1.55)
			(end 1.487 -1.55)
			(stroke
				(width 0.15)
				(type solid)
			)
			(layer "B.Fab")
		)
		(fp_line
			(start 1.487 -1.55)
			(end 1.487 1.551)
			(stroke
				(width 0.15)
				(type solid)
			)
			(layer "B.Fab")
		)
		(fp_text user "Author: Antmicro"
			(at -4.13 -4.52 90)
			(layer "B.Fab")
			(effects
				(font
					(size 0.7 0.7)
					(thickness 0.15)
				)
				(justify left bottom mirror)
			)
		)
		(fp_text user "${REFERENCE}"
			(at -4.13 -6.92 90)
			(layer "B.Fab")
			(effects
				(font
					(size 0.7 0.7)
					(thickness 0.15)
				)
				(justify left bottom mirror)
			)
		)
		(fp_text user "License: Apache-2.0"
			(at -4.13 -5.72 90)
			(layer "B.Fab")
			(effects
				(font
					(size 0.7 0.7)
					(thickness 0.15)
				)
				(justify left bottom mirror)
			)
		)
		(pad "1" smd rect
			(at -0.012 -1.499 270)
			(size 1 1.05)
			(layers "B.Cu" "B.Mask" "B.Paste")
			(net 371 "Net-(J15-Pad1)")
			(pintype "passive")
		)
		(pad "SH1" smd rect
			(at 1.463 0 270)
			(size 1.05 2.2)
			(layers "B.Cu" "B.Mask" "B.Paste")
			(net 1 "GND")
			(pintype "passive")
		)
		(pad "SH2" smd rect
			(at -1.488 0 270)
			(size 1.05 2.2)
			(layers "B.Cu" "B.Mask" "B.Paste")
			(net 1 "GND")
			(pintype "passive")
		)
		(zone
			(net 0)
			(net_name "")
			(layer "B.Cu")
			(hatch edge 0.508)
			(connect_pads
				(clearance 0)
			)
			(min_thickness 0.254)
			(filled_areas_thickness no)
			(keepout
				(tracks not_allowed)
				(vias not_allowed)
				(pads not_allowed)
				(copperpour not_allowed)
				(footprints not_allowed)
			)
			(placement
				(enabled no)
				(sheetname "")
			)
			(fill
				(thermal_gap 0.508)
				(thermal_bridge_width 0.508)
			)
			(polygon
				(pts
					(xy 137.86 103.6) (xy 137.86 101.72) (xy 135.8 101.72) (xy 135.8 103.6)
				)
			)
		)
	)
	(footprint "antmicro-footprints:C_0402_1005Metric_EIA"
		(layer "B.Cu")
		(at 183 147.501 -90)
		(descr "Capacitor SMD 0402 (1005 Metric), square (rectangular) end terminal, IPC_7351 nominal, (Body size source: IPC-SM-782 page 76, https://www.pcb-3d.com/wordpress/wp-content/uploads/ipc-sm-782a_amendment_1_and_2.pdf)")
		(tags "capacitor 0402")
		(property "Reference" "C335"
			(at -12.601 30.7 90)
			(layer "B.SilkS")
			(effects
				(font
					(size 0.7 0.7)
					(thickness 0.15)
				)
				(justify left bottom mirror)
			)
		)
		(property "Value" "C_100n_0402"
			(at 0 -1.169 90)
			(layer "B.Fab")
			(effects
				(font
					(size 0.7 0.7)
					(thickness 0.15)
				)
				(justify left bottom mirror)
			)
		)
		(property "Manufacturer" "Murata"
			(at 0 0 270)
			(unlocked yes)
			(layer "B.Fab")
			(hide yes)
			(effects
				(font
					(size 1 1)
					(thickness 0.15)
				)
				(justify mirror)
			)
		)
		(property "MPN" "GRM155R61H104KE14D"
			(at 0 0 270)
			(unlocked yes)
			(layer "B.Fab")
			(hide yes)
			(effects
				(font
					(size 1 1)
					(thickness 0.15)
				)
				(justify mirror)
			)
		)
		(property "Val" "100n"
			(at 0 0 270)
			(unlocked yes)
			(layer "B.Fab")
			(hide yes)
			(effects
				(font
					(size 1 1)
					(thickness 0.15)
				)
				(justify mirror)
			)
		)
		(property "License" "Apache-2.0"
			(at 0 0 270)
			(unlocked yes)
			(layer "B.Fab")
			(hide yes)
			(effects
				(font
					(size 1 1)
					(thickness 0.15)
				)
				(justify mirror)
			)
		)
		(property "Author" "Antmicro"
			(at 0 0 270)
			(unlocked yes)
			(layer "B.Fab")
			(hide yes)
			(effects
				(font
					(size 1 1)
					(thickness 0.15)
				)
				(justify mirror)
			)
		)
		(property "Voltage" "50V"
			(at 0 0 270)
			(unlocked yes)
			(layer "B.Fab")
			(hide yes)
			(effects
				(font
					(size 1 1)
					(thickness 0.15)
				)
				(justify mirror)
			)
		)
		(property "Dielectric" "X5R"
			(at 0 0 270)
			(unlocked yes)
			(layer "B.Fab")
			(hide yes)
			(effects
				(font
					(size 1 1)
					(thickness 0.15)
				)
				(justify mirror)
			)
		)
		(sheetname "/FPGA banks HP/")
		(sheetfile "fpga-hp-banks.kicad_sch")
		(attr smd)
		(fp_rect
			(start -0.95 0.45)
			(end 0.95 -0.45)
			(stroke
				(width 0.05)
				(type default)
			)
			(fill no)
			(layer "B.CrtYd")
		)
		(fp_line
			(start -0.5 0.25)
			(end 0.498 0.25)
			(stroke
				(width 0.15)
				(type solid)
			)
			(layer "B.Fab")
		)
		(fp_line
			(start 0.498 0.25)
			(end 0.498 -0.248)
			(stroke
				(width 0.15)
				(type solid)
			)
			(layer "B.Fab")
		)
		(fp_line
			(start -0.5 -0.248)
			(end -0.5 0.25)
			(stroke
				(width 0.15)
				(type solid)
			)
			(layer "B.Fab")
		)
		(fp_line
			(start 0.498 -0.248)
			(end -0.5 -0.248)
			(stroke
				(width 0.15)
				(type solid)
			)
			(layer "B.Fab")
		)
		(fp_text user "License: Apache-2.0"
			(at -0.9656 -4.369 90)
			(layer "B.Fab")
			(effects
				(font
					(size 0.7 0.7)
					(thickness 0.15)
				)
				(justify left bottom mirror)
			)
		)
		(fp_text user "Author: Antmicro"
			(at -0.9656 -5.569 90)
			(layer "B.Fab")
			(effects
				(font
					(size 0.7 0.7)
					(thickness 0.15)
				)
				(justify left bottom mirror)
			)
		)
		(fp_text user "${REFERENCE}"
			(at -0.9656 -3.169 90)
			(layer "B.Fab")
			(effects
				(font
					(size 0.7 0.7)
					(thickness 0.15)
				)
				(justify left bottom mirror)
			)
		)
		(pad "1" smd roundrect
			(at -0.5 0 180)
			(size 0.6 0.6)
			(layers "B.Cu" "B.Mask" "B.Paste")
			(roundrect_rratio 0.25)
			(net 545 "/FPGA banks HP/VREF_66")
			(pintype "passive")
		)
		(pad "2" smd roundrect
			(at 0.498 0 270)
			(size 0.6 0.6)
			(layers "B.Cu" "B.Mask" "B.Paste")
			(roundrect_rratio 0.25)
			(net 1 "GND")
			(pintype "passive")
		)
	)
	(footprint "antmicro-footprints:C_0603_1608Metric"
		(layer "B.Cu")
		(at 221.02 172.06 90)
		(descr "Capacitor SMD 0603")
		(tags "capacitor 0603")
		(property "Reference" "C259"
			(at -4.04 0.39 90)
			(layer "B.SilkS")
			(effects
				(font
					(size 0.7 0.7)
					(thickness 0.15)
				)
				(justify right bottom mirror)
			)
		)
		(property "Value" "C_22u_0603"
			(at -1.42757 -1.770288 90)
			(layer "B.Fab")
			(effects
				(font
					(size 0.7 0.7)
					(thickness 0.15)
				)
				(justify right bottom mirror)
			)
		)
		(property "Datasheet" "https://www.murata.com/products/productdetail?partno=GRM188R60J226MEA0%23"
			(at 0 0 90)
			(layer "F.Fab")
			(hide yes)
			(effects
				(font
					(size 1.27 1.27)
					(thickness 0.15)
				)
			)
		)
		(property "Manufacturer" "Murata"
			(at 0 0 90)
			(unlocked yes)
			(layer "B.Fab")
			(hide yes)
			(effects
				(font
					(size 1 1)
					(thickness 0.15)
				)
				(justify mirror)
			)
		)
		(property "MPN" "GRM188R60J226MEA0D"
			(at 0 0 90)
			(unlocked yes)
			(layer "B.Fab")
			(hide yes)
			(effects
				(font
					(size 1 1)
					(thickness 0.15)
				)
				(justify mirror)
			)
		)
		(property "Val" "22u"
			(at 0 0 90)
			(unlocked yes)
			(layer "B.Fab")
			(hide yes)
			(effects
				(font
					(size 1 1)
					(thickness 0.15)
				)
				(justify mirror)
			)
		)
		(property "License" "Apache-2.0"
			(at 0 0 90)
			(unlocked yes)
			(layer "B.Fab")
			(hide yes)
			(effects
				(font
					(size 1 1)
					(thickness 0.15)
				)
				(justify mirror)
			)
		)
		(property "Author" "Antmicro"
			(at 0 0 90)
			(unlocked yes)
			(layer "B.Fab")
			(hide yes)
			(effects
				(font
					(size 1 1)
					(thickness 0.15)
				)
				(justify mirror)
			)
		)
		(property "Voltage" ""
			(at 0 0 90)
			(unlocked yes)
			(layer "B.Fab")
			(hide yes)
			(effects
				(font
					(size 1 1)
					(thickness 0.15)
				)
				(justify mirror)
			)
		)
		(property "Dielectric" ""
			(at 0 0 90)
			(unlocked yes)
			(layer "B.Fab")
			(hide yes)
			(effects
				(font
					(size 1 1)
					(thickness 0.15)
				)
				(justify mirror)
			)
		)
		(sheetname "/Supply/DC-DC VCCINT/")
		(sheetfile "dc-dc-vccint.kicad_sch")
		(attr smd)
		(fp_line
			(start -0.15 -0.4)
			(end 0.15 -0.4)
			(stroke
				(width 0.15)
				(type solid)
			)
			(layer "B.SilkS")
		)
		(fp_line
			(start -0.15 0.4)
			(end 0.15 0.4)
			(stroke
				(width 0.15)
				(type solid)
			)
			(layer "B.SilkS")
		)
		(fp_rect
			(start -1.25 0.65)
			(end 1.25 -0.65)
			(stroke
				(width 0.05)
				(type solid)
			)
			(fill no)
			(layer "B.CrtYd")
		)
		(fp_rect
			(start -0.8 0.4)
			(end 0.8 -0.4)
			(stroke
				(width 0.15)
				(type solid)
			)
			(fill no)
			(layer "B.Fab")
		)
		(fp_text user "License: Apache-2.0"
			(at -1.682 -5.895 270)
			(layer "B.Fab")
			(effects
				(font
					(size 0.7 0.7)
					(thickness 0.15)
				)
				(justify left bottom mirror)
			)
		)
		(fp_text user "${REFERENCE}"
			(at -1.682 -3.895 270)
			(layer "B.Fab")
			(effects
				(font
					(size 0.7 0.7)
					(thickness 0.15)
				)
				(justify left bottom mirror)
			)
		)
		(fp_text user "Author: Antmicro"
			(at -1.682 -4.894 270)
			(layer "B.Fab")
			(effects
				(font
					(size 0.7 0.7)
					(thickness 0.15)
				)
				(justify left bottom mirror)
			)
		)
		(pad "1" smd roundrect
			(at -0.7 0 90)
			(size 0.8 1)
			(layers "B.Cu" "B.Mask" "B.Paste")
			(roundrect_rratio 0.2)
			(net 1 "GND")
			(pintype "passive")
		)
		(pad "2" smd roundrect
			(at 0.7 0 90)
			(size 0.8 1)
			(layers "B.Cu" "B.Mask" "B.Paste")
			(roundrect_rratio 0.2)
			(net 223 "/Supply/DC-DC VCCINT/0V85_REG0")
			(pintype "passive")
		)
	)
)
